FILE_TYPE=LIBRARY_PARTS;
primitive 'TPS2061','TPS2061_SM';
  pin
    'EN_N':
      PIN_NUMBER='(4)';
      INPUT_LOAD='(-0.01,0.01)';
    'GND':
      PIN_NUMBER='(2)';
      PINUSE='GROUND';
      NO_LOAD_CHECK='Both';
      NO_IO_CHECK='Both';
      NO_ASSERT_CHECK='TRUE';
      NO_DIR_CHECK='TRUE';
      ALLOW_CONNECT='TRUE';
    'IN':
      PIN_NUMBER='(5)';
      INPUT_LOAD='(-0.01,0.01)';
    'OC_N':
      PIN_NUMBER='(3)';
      OUTPUT_LOAD='(1.0,-1.0)';
    'OUT':
      PIN_NUMBER='(1)';
      OUTPUT_LOAD='(1.0,-1.0)';
  end_pin;
  body
    PART_NAME='TPS2061';
    PHYS_DES_PREFIX='U';
  end_body;
end_primitive;

END.
